# TIMECARD (Time Appliance Project (Time Card)) — schematic netlist excerpt (pin names and nets, part order shuffled) for the footprints in the layout excerpt that follows; sources: Cadence DE-HDL packaged netlist, KiCad conversion of R4006-B0001-02_R01.brd

C217  CAPACITOR  0.1UF 10V 10%  pkg SMC_0402R_H022  page 14 : \1\ = FPGA_MGTAVTT ; \2\ = SG
C150  CAPACITOR  0.1UF 10V 10%  pkg SMC_0402R_H022  page 14 : \1\ = XP1R8V_FPGA ; \2\ = SG

(kicad_pcb
	(version 20260206)
	(generator "pcbnew")
	(generator_version "10.0")
	(general
		(thickness 1.6)
		(legacy_teardrops no)
	)
	(paper "A4")
	(title_block
		(title "timecard-production-celestica-r4006 — R4006-B0001-02_R01.brd")
		(comment 1 "Time Appliance Project (Time Card) / footprints 936-937 of 1113")
	)
	(layers
		(0 "F.Cu" signal "TOP")
		(4 "In1.Cu" signal "L02_GND1")
		(6 "In2.Cu" signal "L03_SIG1")
		(8 "In3.Cu" signal "L04_GND2")
		(10 "In4.Cu" signal "L05_VCC1")
		(12 "In5.Cu" signal "L06_VCC2")
		(14 "In6.Cu" signal "L07_GND3")
		(16 "In7.Cu" signal "L08_SIG2")
		(18 "In8.Cu" signal "L09_GND4")
		(2 "B.Cu" signal "BOTTOM")
		(9 "F.Adhes" user "F.Adhesive")
		(11 "B.Adhes" user "B.Adhesive")
		(13 "F.Paste" user "Package Geometry/Pastemask Top")
		(15 "B.Paste" user "Package Geometry/Pastemask Bottom")
		(5 "F.SilkS" user "Ref Des/Silkscreen Top")
		(7 "B.SilkS" user "Ref Des/Silkscreen Bottom")
		(1 "F.Mask" user "Board Geometry/Soldermask Top")
		(3 "B.Mask" user "Board Geometry/Soldermask Bottom")
		(17 "Dwgs.User" user "User.Drawings")
		(19 "Cmts.User" user "User.Comments")
		(21 "Eco1.User" user "User.Eco1")
		(23 "Eco2.User" user "User.Eco2")
		(25 "Edge.Cuts" user "Board Geometry/Outline")
		(27 "Margin" user)
		(31 "F.CrtYd" user "Package Geometry/Place Bound Top")
		(29 "B.CrtYd" user "Package Geometry/Place Bound Bottom")
		(35 "F.Fab" user "Ref Des/Assembly Top")
		(33 "B.Fab" user "Ref Des/Assembly Bottom")
	)
	(footprint ""
		(layer "B.Cu")
		(at 92.202 -55.118 180)
		(property "Reference" "C150"
			(at -0.508 -1.94437 0)
			(unlocked yes)
			(layer "B.SilkS")
			(effects
				(font
					(size 0.7874 0.5842)
					(thickness 0.1524)
				)
				(justify mirror)
			)
		)
		(property "Value" "VAL*"
			(at -0.0762 2.067306 180)
			(unlocked yes)
			(layer "B.Fab")
			(hide yes)
			(effects
				(font
					(size 0.7874 0.5842)
					(thickness 0.1524)
				)
				(justify mirror)
			)
		)
		(property "Device Type" "CAPACITOR-G105-0B104-CK,0.1UF,A"
			(at -0.0508 1.127506 180)
			(unlocked yes)
			(layer "B.Fab")
			(hide yes)
			(effects
				(font
					(size 0.7874 0.5842)
					(thickness 0.1524)
				)
				(justify mirror)
			)
		)
		(property "User Part Number" "PARTNUM*"
			(at -0.1016 4.023106 180)
			(unlocked yes)
			(layer "Cmts.User")
			(hide yes)
			(effects
				(font
					(size 0.7874 0.5842)
					(thickness 0.1524)
				)
				(justify mirror)
			)
		)
		(property "Tolerance" "TOL*"
			(at -0.0762 3.032506 180)
			(unlocked yes)
			(layer "Cmts.User")
			(hide yes)
			(effects
				(font
					(size 0.7874 0.5842)
					(thickness 0.1524)
				)
				(justify mirror)
			)
		)
		(duplicate_pad_numbers_are_jumpers no)
		(fp_line
			(start 1.143 0.5588)
			(end -1.143 0.5588)
			(stroke
				(width 0.1)
				(type default)
			)
			(layer "B.SilkS")
		)
		(fp_line
			(start 1.143 -0.5588)
			(end 1.143 0.5588)
			(stroke
				(width 0.1)
				(type default)
			)
			(layer "B.SilkS")
		)
		(fp_line
			(start -1.143 0.5588)
			(end -1.143 -0.5588)
			(stroke
				(width 0.1)
				(type default)
			)
			(layer "B.SilkS")
		)
		(fp_line
			(start -1.143 -0.5588)
			(end 1.143 -0.5588)
			(stroke
				(width 0.1)
				(type default)
			)
			(layer "B.SilkS")
		)
		(fp_rect
			(start -1.143 0.5588)
			(end 1.143 -0.5588)
			(stroke
				(width 0)
				(type default)
			)
			(fill no)
			(layer "B.CrtYd")
		)
		(fp_line
			(start 0.508 0.3048)
			(end -0.508 0.3048)
			(stroke
				(width 0.1)
				(type default)
			)
			(layer "B.Fab")
		)
		(fp_line
			(start 0.508 -0.3048)
			(end 0.508 0.3048)
			(stroke
				(width 0.1)
				(type default)
			)
			(layer "B.Fab")
		)
		(fp_line
			(start -0.508 0.3048)
			(end -0.508 -0.3048)
			(stroke
				(width 0.1)
				(type default)
			)
			(layer "B.Fab")
		)
		(fp_line
			(start -0.508 -0.3048)
			(end 0.508 -0.3048)
			(stroke
				(width 0.1)
				(type default)
			)
			(layer "B.Fab")
		)
		(pad "1" smd rect
			(at 0.5334 0)
			(size 0.7112 0.6096)
			(layers "B.Cu" "B.Mask" "B.Paste")
			(net "XP1R8V_FPGA")
		)
		(pad "2" smd rect
			(at -0.5334 0)
			(size 0.7112 0.6096)
			(layers "B.Cu" "B.Mask" "B.Paste")
			(net "SG")
		)
		(zone
			(layer "B.Cu")
			(hatch none 0.5)
			(connect_pads
				(clearance 0)
			)
			(min_thickness 0.25)
			(keepout
				(tracks allowed)
				(vias not_allowed)
				(pads allowed)
				(copperpour not_allowed)
				(footprints allowed)
			)
			(placement
				(enabled no)
				(sheetname "")
			)
			(fill
				(thermal_gap 0.5)
				(thermal_bridge_width 0.5)
				(island_removal_mode 0)
			)
			(polygon
				(pts
					(xy 92.2782 -55.4228) (xy 92.1258 -55.4228) (xy 92.1258 -54.8132) (xy 92.2782 -54.8132)
				)
			)
		)
	)
	(footprint ""
		(layer "B.Cu")
		(at 100.84689 -37.323268 -90)
		(property "Reference" "C217"
			(at 1.524508 42.01922 270)
			(unlocked yes)
			(layer "B.SilkS")
			(effects
				(font
					(size 0.635 0.4064)
					(thickness 0.1524)
				)
				(justify mirror)
			)
		)
		(property "Value" "VAL*"
			(at 0 3.718306 270)
			(unlocked yes)
			(layer "B.Fab")
			(hide yes)
			(effects
				(font
					(size 0.7874 0.5842)
					(thickness 0.127)
				)
				(justify mirror)
			)
		)
		(property "Tolerance" "TOL*"
			(at 0 4.861306 270)
			(unlocked yes)
			(layer "Cmts.User")
			(hide yes)
			(effects
				(font
					(size 0.7874 0.5842)
					(thickness 0.127)
				)
				(justify mirror)
			)
		)
		(property "User Part Number" "PARTNUM*"
			(at 0 2.575306 270)
			(unlocked yes)
			(layer "Cmts.User")
			(hide yes)
			(effects
				(font
					(size 0.7874 0.5842)
					(thickness 0.127)
				)
				(justify mirror)
			)
		)
		(property "Device Type" "CAPACITOR-G105-0B104-CK,0.1UF,A"
			(at 0 1.432306 270)
			(unlocked yes)
			(layer "B.Fab")
			(hide yes)
			(effects
				(font
					(size 0.7874 0.5842)
					(thickness 0.127)
				)
				(justify mirror)
			)
		)
		(duplicate_pad_numbers_are_jumpers no)
		(fp_line
			(start -0.970026 0.4699)
			(end 0.970026 0.4699)
			(stroke
				(width 0.1)
				(type default)
			)
			(layer "B.SilkS")
		)
		(fp_line
			(start 0.970026 0.4699)
			(end 0.970026 -0.4699)
			(stroke
				(width 0.1)
				(type default)
			)
			(layer "B.SilkS")
		)
		(fp_line
			(start -0.970026 -0.4699)
			(end -0.970026 0.4699)
			(stroke
				(width 0.1)
				(type default)
			)
			(layer "B.SilkS")
		)
		(fp_line
			(start 0.970026 -0.4699)
			(end -0.970026 -0.4699)
			(stroke
				(width 0.1)
				(type default)
			)
			(layer "B.SilkS")
		)
		(fp_poly
			(pts
				(xy 0.970026 0.4699) (xy -0.970026 0.4699) (xy -0.970026 -0.4699) (xy 0.970026 -0.4699)
			)
			(stroke
				(width 0)
				(type default)
			)
			(fill no)
			(layer "B.CrtYd")
		)
		(fp_line
			(start -0.508 0.3048)
			(end 0.508 0.3048)
			(stroke
				(width 0.1)
				(type default)
			)
			(layer "B.Fab")
		)
		(fp_line
			(start 0.508 0.3048)
			(end 0.508 -0.3048)
			(stroke
				(width 0.1)
				(type default)
			)
			(layer "B.Fab")
		)
		(fp_line
			(start -0.508 -0.3048)
			(end -0.508 0.3048)
			(stroke
				(width 0.1)
				(type default)
			)
			(layer "B.Fab")
		)
		(fp_line
			(start 0.508 -0.3048)
			(end -0.508 -0.3048)
			(stroke
				(width 0.1)
				(type default)
			)
			(layer "B.Fab")
		)
		(pad "1" smd circle
			(at 0.500126 0 90)
			(size 0.635 0.635)
			(layers "B.Cu" "B.Mask" "B.Paste")
			(net "FPGA_MGTAVTT")
		)
		(pad "2" smd circle
			(at -0.500126 0 90)
			(size 0.635 0.635)
			(layers "B.Cu" "B.Mask" "B.Paste")
			(net "SG")
		)
	)
)
